# T6G (Grand Teton) — schematic netlist excerpt (pin names and nets, part order shuffled) for the footprints in the layout excerpt that follows; sources: Cadence DE-HDL packaged netlist, KiCad conversion of 04192023_DAF0TMB3IC0_F0TG_MB_C_brd_V02_OCP.brd

PC192  Q_CAP  560PF 50V 10% EMPTY  pkg C0402  page 202 : A = SW_PVDDCR_CPU1_P0_SW3 ; B = SW_PVDDCR_CPU1_P0_SW3_RC
R951  Q_RES  0 5% EMPTY  pkg 0402LF  page 279 : A = P1V8_CPU0_RT0_1A_1D ; B = P1V8_CPU0_RT0_1A

(kicad_pcb
	(version 20260206)
	(generator "pcbnew")
	(generator_version "10.0")
	(general
		(thickness 1.6)
		(legacy_teardrops no)
	)
	(paper "A4")
	(title_block
		(title "04192023_DAF0TMB3IC0_F0TG_MB_C_brd_V02_OCP.brd")
		(comment 1 "Grand Teton / footprints 3875-3876 of 8354")
	)
	(layers
		(0 "F.Cu" signal "TOP")
		(4 "In1.Cu" signal "GND")
		(6 "In2.Cu" signal "IN1")
		(8 "In3.Cu" signal "GND1")
		(10 "In4.Cu" signal "IN2")
		(12 "In5.Cu" signal "GND2")
		(14 "In6.Cu" signal "IN3")
		(16 "In7.Cu" signal "GND3")
		(18 "In8.Cu" signal "VCC")
		(20 "In9.Cu" signal "VCC1")
		(22 "In10.Cu" signal "GND4")
		(24 "In11.Cu" signal "IN4")
		(26 "In12.Cu" signal "GND5")
		(28 "In13.Cu" signal "IN5")
		(30 "In14.Cu" signal "GND6")
		(32 "In15.Cu" signal "IN6")
		(34 "In16.Cu" signal "GND7")
		(2 "B.Cu" signal "BOTTOM")
		(9 "F.Adhes" user "F.Adhesive")
		(11 "B.Adhes" user "B.Adhesive")
		(13 "F.Paste" user "Package Geometry/Pastemask Top")
		(15 "B.Paste" user "Package Geometry/Pastemask Bottom")
		(5 "F.SilkS" user "Ref Des/Silkscreen Top")
		(7 "B.SilkS" user "Ref Des/Silkscreen Bottom")
		(1 "F.Mask" user "Board Geometry/Soldermask Top")
		(3 "B.Mask" user "Board Geometry/Soldermask Bottom")
		(17 "Dwgs.User" user "User.Drawings")
		(19 "Cmts.User" user "User.Comments")
		(21 "Eco1.User" user "User.Eco1")
		(23 "Eco2.User" user "User.Eco2")
		(25 "Edge.Cuts" user "Board Geometry/Outline")
		(27 "Margin" user)
		(31 "F.CrtYd" user "Package Geometry/Place Bound Top")
		(29 "B.CrtYd" user "Package Geometry/Place Bound Bottom")
		(35 "F.Fab" user "Ref Des/Assembly Top")
		(33 "B.Fab" user "Ref Des/Assembly Bottom")
	)
	(footprint ""
		(layer "F.Cu")
		(at 314.651898 -331.990954 180)
		(property "Reference" "PC192"
			(at 0 0 180)
			(layer "F.SilkS")
			(hide yes)
			(effects
				(font
					(size 1.27 1.27)
				)
			)
		)
		(property "Value" ""
			(at 0 0 180)
			(layer "F.Fab")
			(effects
				(font
					(size 1.27 1.27)
				)
			)
		)
		(duplicate_pad_numbers_are_jumpers no)
		(fp_line
			(start 0.7874 0.4064)
			(end -0.7874 0.4064)
			(stroke
				(width 0.1524)
				(type default)
			)
			(layer "F.SilkS")
		)
		(fp_line
			(start 0.7874 -0.4064)
			(end 0.7874 0.4064)
			(stroke
				(width 0.1524)
				(type default)
			)
			(layer "F.SilkS")
		)
		(fp_line
			(start -0.7874 0.4064)
			(end -0.7874 -0.4064)
			(stroke
				(width 0.1524)
				(type default)
			)
			(layer "F.SilkS")
		)
		(fp_line
			(start -0.7874 -0.4064)
			(end 0.7874 -0.4064)
			(stroke
				(width 0.1524)
				(type default)
			)
			(layer "F.SilkS")
		)
		(fp_line
			(start 0.67945 0.3048)
			(end 0.120396 0.3048)
			(stroke
				(width 0.1)
				(type default)
			)
			(layer "F.Fab")
		)
		(fp_line
			(start 0.67945 -0.3048)
			(end 0.67945 0.3048)
			(stroke
				(width 0.1)
				(type default)
			)
			(layer "F.Fab")
		)
		(fp_line
			(start 0.12065 -0.2794)
			(end 0.12065 -0.3048)
			(stroke
				(width 0.1)
				(type default)
			)
			(layer "F.Fab")
		)
		(fp_line
			(start 0.12065 -0.3048)
			(end 0.67945 -0.3048)
			(stroke
				(width 0.1)
				(type default)
			)
			(layer "F.Fab")
		)
		(fp_line
			(start 0.120396 0.3048)
			(end 0.120396 0.2794)
			(stroke
				(width 0.1)
				(type default)
			)
			(layer "F.Fab")
		)
		(fp_line
			(start 0.120396 0.2794)
			(end -0.12065 0.2794)
			(stroke
				(width 0.1)
				(type default)
			)
			(layer "F.Fab")
		)
		(fp_line
			(start -0.12065 0.3048)
			(end -0.67945 0.3048)
			(stroke
				(width 0.1)
				(type default)
			)
			(layer "F.Fab")
		)
		(fp_line
			(start -0.12065 0.2794)
			(end -0.12065 0.3048)
			(stroke
				(width 0.1)
				(type default)
			)
			(layer "F.Fab")
		)
		(fp_line
			(start -0.12065 -0.2794)
			(end 0.12065 -0.2794)
			(stroke
				(width 0.1)
				(type default)
			)
			(layer "F.Fab")
		)
		(fp_line
			(start -0.12065 -0.305054)
			(end -0.12065 -0.2794)
			(stroke
				(width 0.1)
				(type default)
			)
			(layer "F.Fab")
		)
		(fp_line
			(start -0.67945 0.3048)
			(end -0.67945 -0.305054)
			(stroke
				(width 0.1)
				(type default)
			)
			(layer "F.Fab")
		)
		(fp_line
			(start -0.67945 -0.305054)
			(end -0.12065 -0.305054)
			(stroke
				(width 0.1)
				(type default)
			)
			(layer "F.Fab")
		)
		(pad "1" smd circle
			(at -0.40005 0 180)
			(size 0 0)
			(layers "F.Cu" "F.Mask" "F.Paste")
			(net "SW_PVDDCR_CPU1_P0_SW3")
		)
		(pad "2" smd circle
			(at 0.40005 0 180)
			(size 0 0)
			(layers "F.Cu" "F.Mask" "F.Paste")
			(net "SW_PVDDCR_CPU1_P0_SW3_RC")
		)
	)
	(footprint ""
		(layer "F.Cu")
		(at 325.862188 -393.47648 180)
		(property "Reference" "R951"
			(at 0 0 180)
			(layer "F.SilkS")
			(hide yes)
			(effects
				(font
					(size 1.27 1.27)
				)
			)
		)
		(property "Value" ""
			(at 0 0 180)
			(layer "F.Fab")
			(effects
				(font
					(size 1.27 1.27)
				)
			)
		)
		(duplicate_pad_numbers_are_jumpers no)
		(fp_line
			(start 0.7874 0.4064)
			(end -0.7874 0.4064)
			(stroke
				(width 0.1524)
				(type default)
			)
			(layer "F.SilkS")
		)
		(fp_line
			(start 0.7874 -0.4064)
			(end 0.7874 0.4064)
			(stroke
				(width 0.1524)
				(type default)
			)
			(layer "F.SilkS")
		)
		(fp_line
			(start -0.7874 0.4064)
			(end -0.7874 -0.4064)
			(stroke
				(width 0.1524)
				(type default)
			)
			(layer "F.SilkS")
		)
		(fp_line
			(start -0.7874 -0.4064)
			(end 0.7874 -0.4064)
			(stroke
				(width 0.1524)
				(type default)
			)
			(layer "F.SilkS")
		)
		(fp_line
			(start 0.67945 0.3048)
			(end 0.120396 0.3048)
			(stroke
				(width 0.1)
				(type default)
			)
			(layer "F.Fab")
		)
		(fp_line
			(start 0.67945 -0.3048)
			(end 0.67945 0.3048)
			(stroke
				(width 0.1)
				(type default)
			)
			(layer "F.Fab")
		)
		(fp_line
			(start 0.12065 -0.2794)
			(end 0.12065 -0.3048)
			(stroke
				(width 0.1)
				(type default)
			)
			(layer "F.Fab")
		)
		(fp_line
			(start 0.12065 -0.3048)
			(end 0.67945 -0.3048)
			(stroke
				(width 0.1)
				(type default)
			)
			(layer "F.Fab")
		)
		(fp_line
			(start 0.120396 0.3048)
			(end 0.120396 0.2794)
			(stroke
				(width 0.1)
				(type default)
			)
			(layer "F.Fab")
		)
		(fp_line
			(start 0.120396 0.2794)
			(end -0.12065 0.2794)
			(stroke
				(width 0.1)
				(type default)
			)
			(layer "F.Fab")
		)
		(fp_line
			(start -0.12065 0.3048)
			(end -0.67945 0.3048)
			(stroke
				(width 0.1)
				(type default)
			)
			(layer "F.Fab")
		)
		(fp_line
			(start -0.12065 0.2794)
			(end -0.12065 0.3048)
			(stroke
				(width 0.1)
				(type default)
			)
			(layer "F.Fab")
		)
		(fp_line
			(start -0.12065 -0.2794)
			(end 0.12065 -0.2794)
			(stroke
				(width 0.1)
				(type default)
			)
			(layer "F.Fab")
		)
		(fp_line
			(start -0.12065 -0.305054)
			(end -0.12065 -0.2794)
			(stroke
				(width 0.1)
				(type default)
			)
			(layer "F.Fab")
		)
		(fp_line
			(start -0.67945 0.3048)
			(end -0.67945 -0.305054)
			(stroke
				(width 0.1)
				(type default)
			)
			(layer "F.Fab")
		)
		(fp_line
			(start -0.67945 -0.305054)
			(end -0.12065 -0.305054)
			(stroke
				(width 0.1)
				(type default)
			)
			(layer "F.Fab")
		)
		(pad "1" smd rect
			(at -0.40005 0)
			(size 0.4572 0.508)
			(layers "F.Cu" "F.Mask" "F.Paste")
			(net "P1V8_CPU0_RT0_1A_1D")
		)
		(pad "2" smd rect
			(at 0.40005 0)
			(size 0.4572 0.508)
			(layers "F.Cu" "F.Mask" "F.Paste")
			(net "P1V8_CPU0_RT0_1A")
		)
	)
)
